(kicad_pcb
	(version 20260206)
	(generator "pcbnew")
	(generator_version "10.0")
	(general
		(thickness 1.6)
		(legacy_teardrops no)
	)
	(paper "A4")
	(title_block
		(title "peb — Lightning_PEB_BRD.brd")
		(comment 1 "Lightning (Wiwynn / Facebook NVMe JBOF) / footprint 139 of 2563 (CN16), pads 77-153 of 166")
	)
	(layers
		(0 "F.Cu" signal "TOP")
		(4 "In1.Cu" signal "L2GND")
		(6 "In2.Cu" signal "L3")
		(8 "In3.Cu" signal "L4VCC")
		(10 "In4.Cu" signal "L5VCC")
		(12 "In5.Cu" signal "L6")
		(14 "In6.Cu" signal "L7GND")
		(2 "B.Cu" signal "BOTTOM")
		(9 "F.Adhes" user "F.Adhesive")
		(11 "B.Adhes" user "B.Adhesive")
		(13 "F.Paste" user "Package Geometry/Pastemask Top")
		(15 "B.Paste" user "Package Geometry/Pastemask Bottom")
		(5 "F.SilkS" user "Ref Des/Silkscreen Top")
		(7 "B.SilkS" user "Ref Des/Silkscreen Bottom")
		(1 "F.Mask" user "Board Geometry/Soldermask Top")
		(3 "B.Mask" user "Board Geometry/Soldermask Bottom")
		(17 "Dwgs.User" user "User.Drawings")
		(19 "Cmts.User" user "User.Comments")
		(21 "Eco1.User" user "User.Eco1")
		(23 "Eco2.User" user "User.Eco2")
		(25 "Edge.Cuts" user "Board Geometry/Outline")
		(27 "Margin" user)
		(31 "F.CrtYd" user "Package Geometry/Place Bound Top")
		(29 "B.CrtYd" user "Package Geometry/Place Bound Bottom")
		(35 "F.Fab" user "Ref Des/Assembly Top")
		(33 "B.Fab" user "Ref Des/Assembly Bottom")
	)
	(footprint ""
		(layer "F.Cu")
		(at 305.63439 -9.53008)
		(property "Reference" "CN16"
			(at 0 0 0)
			(layer "F.SilkS")
			(hide yes)
			(effects
				(font
					(size 1.27 1.27)
				)
			)
		)
		(property "Value" "MLX-CONN144-12R-3-GP-U2"
			(at -33.7693 -12.9032 0)
			(unlocked yes)
			(layer "F.Fab")
			(hide yes)
			(effects
				(font
					(size 1.016 1.016)
					(thickness 0.1524)
				)
			)
		)
		(property "Device Type" "PREFIT-144P-459383U2H519"
			(at -33.7693 -14.4272 0)
			(unlocked yes)
			(layer "F.Fab")
			(hide yes)
			(effects
				(font
					(size 1.016 1.016)
					(thickness 0.1524)
				)
			)
		)
		(duplicate_pad_numbers_are_jumpers no)
		(pad "CA5" thru_hole circle
			(at 5.500116 -2.999994)
			(size 0.7366 0.7366)
			(drill 0.369824)
			(layers "*.Cu" "*.Mask")
			(remove_unused_layers no)
			(net "PCIE_RX_N8")
			(clearance 0.1778)
			(thermal_gap 0.1778)
		)
		(pad "CA6" thru_hole circle
			(at 6.249924 -3.700018)
			(size 0.7366 0.7366)
			(drill 0.369824)
			(layers "*.Cu" "*.Mask")
			(remove_unused_layers no)
			(net "GND")
			(clearance 0.1778)
			(thermal_gap 0.1778)
		)
		(pad "CA7" thru_hole circle
			(at 6.999986 -4.400042)
			(size 0.7366 0.7366)
			(drill 0.369824)
			(layers "*.Cu" "*.Mask")
			(remove_unused_layers no)
			(net "PCIE_RX_P11")
			(clearance 0.1778)
			(thermal_gap 0.1778)
		)
		(pad "CA8" thru_hole circle
			(at 7.750048 -2.999994)
			(size 0.7366 0.7366)
			(drill 0.369824)
			(layers "*.Cu" "*.Mask")
			(remove_unused_layers no)
			(net "PCIE_RX_N11")
			(clearance 0.1778)
			(thermal_gap 0.1778)
		)
		(pad "CA9" thru_hole circle
			(at 8.50011 -3.700018)
			(size 0.7366 0.7366)
			(drill 0.369824)
			(layers "*.Cu" "*.Mask")
			(remove_unused_layers no)
			(net "GND")
			(clearance 0.1778)
			(thermal_gap 0.1778)
		)
		(pad "CB1" thru_hole circle
			(at 2.500122 -8.199882)
			(size 0.7366 0.7366)
			(drill 0.369824)
			(layers "*.Cu" "*.Mask")
			(remove_unused_layers no)
			(net "HOST7_RST_N_C")
			(clearance 0.1778)
			(thermal_gap 0.1778)
		)
		(pad "CB2" thru_hole circle
			(at 3.24993 -6.800088)
			(size 0.7366 0.7366)
			(drill 0.369824)
			(layers "*.Cu" "*.Mask")
			(remove_unused_layers no)
			(net "8644_SDA_R_7")
			(clearance 0.1778)
			(thermal_gap 0.1778)
		)
		(pad "CB3" thru_hole circle
			(at 3.999992 -7.500112)
			(size 0.7366 0.7366)
			(drill 0.369824)
			(layers "*.Cu" "*.Mask")
			(remove_unused_layers no)
			(net "GND")
			(clearance 0.1778)
			(thermal_gap 0.1778)
		)
		(pad "CB4" thru_hole circle
			(at 4.750054 -8.199882)
			(size 0.7366 0.7366)
			(drill 0.369824)
			(layers "*.Cu" "*.Mask")
			(remove_unused_layers no)
			(net "PCIE_RX_P9")
			(clearance 0.1778)
			(thermal_gap 0.1778)
		)
		(pad "CB5" thru_hole circle
			(at 5.500116 -6.800088)
			(size 0.7366 0.7366)
			(drill 0.369824)
			(layers "*.Cu" "*.Mask")
			(remove_unused_layers no)
			(net "PCIE_RX_N9")
			(clearance 0.1778)
			(thermal_gap 0.1778)
		)
		(pad "CB6" thru_hole circle
			(at 6.249924 -7.500112)
			(size 0.7366 0.7366)
			(drill 0.369824)
			(layers "*.Cu" "*.Mask")
			(remove_unused_layers no)
			(net "GND")
			(clearance 0.1778)
			(thermal_gap 0.1778)
		)
		(pad "CB7" thru_hole circle
			(at 6.999986 -8.199882)
			(size 0.7366 0.7366)
			(drill 0.369824)
			(layers "*.Cu" "*.Mask")
			(remove_unused_layers no)
			(net "PCIE_RX_P10")
			(clearance 0.1778)
			(thermal_gap 0.1778)
		)
		(pad "CB8" thru_hole circle
			(at 7.750048 -6.800088)
			(size 0.7366 0.7366)
			(drill 0.369824)
			(layers "*.Cu" "*.Mask")
			(remove_unused_layers no)
			(net "PCIE_RX_N10")
			(clearance 0.1778)
			(thermal_gap 0.1778)
		)
		(pad "CB9" thru_hole circle
			(at 8.50011 -7.500112)
			(size 0.7366 0.7366)
			(drill 0.369824)
			(layers "*.Cu" "*.Mask")
			(remove_unused_layers no)
			(net "GND")
			(clearance 0.1778)
			(thermal_gap 0.1778)
		)
		(pad "CC1" thru_hole circle
			(at 2.500122 -11.999976)
			(size 0.7366 0.7366)
			(drill 0.369824)
			(layers "*.Cu" "*.Mask")
			(remove_unused_layers no)
			(net "BMC_I2C13_MINI7_SCL")
			(clearance 0.1778)
			(thermal_gap 0.1778)
		)
		(pad "CC2" thru_hole circle
			(at 3.24993 -10.599928)
			(size 0.7366 0.7366)
			(drill 0.369824)
			(layers "*.Cu" "*.Mask")
			(remove_unused_layers no)
			(net "8644_CBL_PRSNT_R_7")
			(clearance 0.1778)
			(thermal_gap 0.1778)
		)
		(pad "CC3" thru_hole circle
			(at 3.999992 -11.299952)
			(size 0.7366 0.7366)
			(drill 0.369824)
			(layers "*.Cu" "*.Mask")
			(remove_unused_layers no)
			(net "GND")
			(clearance 0.1778)
			(thermal_gap 0.1778)
		)
		(pad "CC4" thru_hole circle
			(at 4.750054 -11.999976)
			(size 0.7366 0.7366)
			(drill 0.369824)
			(layers "*.Cu" "*.Mask")
			(remove_unused_layers no)
			(net "PCIE_TX_P8")
			(clearance 0.1778)
			(thermal_gap 0.1778)
		)
		(pad "CC5" thru_hole circle
			(at 5.500116 -10.599928)
			(size 0.7366 0.7366)
			(drill 0.369824)
			(layers "*.Cu" "*.Mask")
			(remove_unused_layers no)
			(net "PCIE_TX_N8")
			(clearance 0.1778)
			(thermal_gap 0.1778)
		)
		(pad "CC6" thru_hole circle
			(at 6.249924 -11.299952)
			(size 0.7366 0.7366)
			(drill 0.369824)
			(layers "*.Cu" "*.Mask")
			(remove_unused_layers no)
			(net "GND")
			(clearance 0.1778)
			(thermal_gap 0.1778)
		)
		(pad "CC7" thru_hole circle
			(at 6.999986 -11.999976)
			(size 0.7366 0.7366)
			(drill 0.369824)
			(layers "*.Cu" "*.Mask")
			(remove_unused_layers no)
			(net "PCIE_TX_P11")
			(clearance 0.1778)
			(thermal_gap 0.1778)
		)
		(pad "CC8" thru_hole circle
			(at 7.750048 -10.599928)
			(size 0.7366 0.7366)
			(drill 0.369824)
			(layers "*.Cu" "*.Mask")
			(remove_unused_layers no)
			(net "PCIE_TX_N11")
			(clearance 0.1778)
			(thermal_gap 0.1778)
		)
		(pad "CC9" thru_hole circle
			(at 8.50011 -11.299952)
			(size 0.7366 0.7366)
			(drill 0.369824)
			(layers "*.Cu" "*.Mask")
			(remove_unused_layers no)
			(net "GND")
			(clearance 0.1778)
			(thermal_gap 0.1778)
		)
		(pad "CD1" thru_hole circle
			(at 2.500122 -15.80007)
			(size 0.7366 0.7366)
			(drill 0.369824)
			(layers "*.Cu" "*.Mask")
			(remove_unused_layers no)
			(net "8644_USB_DN7")
			(clearance 0.1778)
			(thermal_gap 0.1778)
		)
		(pad "CD2" thru_hole circle
			(at 3.24993 -14.400022)
			(size 0.7366 0.7366)
			(drill 0.369824)
			(layers "*.Cu" "*.Mask")
			(remove_unused_layers no)
			(net "8644_USB_DP7")
			(clearance 0.1778)
			(thermal_gap 0.1778)
		)
		(pad "CD3" thru_hole circle
			(at 3.999992 -15.100046)
			(size 0.7366 0.7366)
			(drill 0.369824)
			(layers "*.Cu" "*.Mask")
			(remove_unused_layers no)
			(net "GND")
			(clearance 0.1778)
			(thermal_gap 0.1778)
		)
		(pad "CD4" thru_hole circle
			(at 4.750054 -15.80007)
			(size 0.7366 0.7366)
			(drill 0.369824)
			(layers "*.Cu" "*.Mask")
			(remove_unused_layers no)
			(net "PCIE_TX_P9")
			(clearance 0.1778)
			(thermal_gap 0.1778)
		)
		(pad "CD5" thru_hole circle
			(at 5.500116 -14.400022)
			(size 0.7366 0.7366)
			(drill 0.369824)
			(layers "*.Cu" "*.Mask")
			(remove_unused_layers no)
			(net "PCIE_TX_N9")
			(clearance 0.1778)
			(thermal_gap 0.1778)
		)
		(pad "CD6" thru_hole circle
			(at 6.249924 -15.100046)
			(size 0.7366 0.7366)
			(drill 0.369824)
			(layers "*.Cu" "*.Mask")
			(remove_unused_layers no)
			(net "GND")
			(clearance 0.1778)
			(thermal_gap 0.1778)
		)
		(pad "CD7" thru_hole circle
			(at 6.999986 -15.80007)
			(size 0.7366 0.7366)
			(drill 0.369824)
			(layers "*.Cu" "*.Mask")
			(remove_unused_layers no)
			(net "PCIE_TX_P10")
			(clearance 0.1778)
			(thermal_gap 0.1778)
		)
		(pad "CD8" thru_hole circle
			(at 7.750048 -14.400022)
			(size 0.7366 0.7366)
			(drill 0.369824)
			(layers "*.Cu" "*.Mask")
			(remove_unused_layers no)
			(net "PCIE_TX_N10")
			(clearance 0.1778)
			(thermal_gap 0.1778)
		)
		(pad "CD9" thru_hole circle
			(at 8.50011 -15.100046)
			(size 0.7366 0.7366)
			(drill 0.369824)
			(layers "*.Cu" "*.Mask")
			(remove_unused_layers no)
			(net "GND")
			(clearance 0.1778)
			(thermal_gap 0.1778)
		)
		(pad "DA1" thru_hole circle
			(at 13.5001 -4.400042)
			(size 0.7366 0.7366)
			(drill 0.369824)
			(layers "*.Cu" "*.Mask")
			(remove_unused_layers no)
			(net "CLK_P_8")
			(clearance 0.1778)
			(thermal_gap 0.1778)
		)
		(pad "DA2" thru_hole circle
			(at 14.249908 -2.999994)
			(size 0.7366 0.7366)
			(drill 0.369824)
			(layers "*.Cu" "*.Mask")
			(remove_unused_layers no)
			(net "CLK_N_8")
			(clearance 0.1778)
			(thermal_gap 0.1778)
		)
		(pad "DA3" thru_hole circle
			(at 14.99997 -3.700018)
			(size 0.7366 0.7366)
			(drill 0.369824)
			(layers "*.Cu" "*.Mask")
			(remove_unused_layers no)
			(net "GND")
			(clearance 0.1778)
			(thermal_gap 0.1778)
		)
		(pad "DA4" thru_hole circle
			(at 15.750032 -4.400042)
			(size 0.7366 0.7366)
			(drill 0.369824)
			(layers "*.Cu" "*.Mask")
			(remove_unused_layers no)
			(net "PCIE_RX_P12")
			(clearance 0.1778)
			(thermal_gap 0.1778)
		)
		(pad "DA5" thru_hole circle
			(at 16.500094 -2.999994)
			(size 0.7366 0.7366)
			(drill 0.369824)
			(layers "*.Cu" "*.Mask")
			(remove_unused_layers no)
			(net "PCIE_RX_N12")
			(clearance 0.1778)
			(thermal_gap 0.1778)
		)
		(pad "DA6" thru_hole circle
			(at 17.249902 -3.700018)
			(size 0.7366 0.7366)
			(drill 0.369824)
			(layers "*.Cu" "*.Mask")
			(remove_unused_layers no)
			(net "GND")
			(clearance 0.1778)
			(thermal_gap 0.1778)
		)
		(pad "DA7" thru_hole circle
			(at 17.999964 -4.400042)
			(size 0.7366 0.7366)
			(drill 0.369824)
			(layers "*.Cu" "*.Mask")
			(remove_unused_layers no)
			(net "PCIE_RX_P15")
			(clearance 0.1778)
			(thermal_gap 0.1778)
		)
		(pad "DA8" thru_hole circle
			(at 18.750026 -2.999994)
			(size 0.7366 0.7366)
			(drill 0.369824)
			(layers "*.Cu" "*.Mask")
			(remove_unused_layers no)
			(net "PCIE_RX_N15")
			(clearance 0.1778)
			(thermal_gap 0.1778)
		)
		(pad "DA9" thru_hole circle
			(at 19.500088 -3.700018)
			(size 0.7366 0.7366)
			(drill 0.369824)
			(layers "*.Cu" "*.Mask")
			(remove_unused_layers no)
			(net "GND")
			(clearance 0.1778)
			(thermal_gap 0.1778)
		)
		(pad "DB1" thru_hole circle
			(at 13.5001 -8.199882)
			(size 0.7366 0.7366)
			(drill 0.369824)
			(layers "*.Cu" "*.Mask")
			(remove_unused_layers no)
			(net "HOST8_RST_N_C")
			(clearance 0.1778)
			(thermal_gap 0.1778)
		)
		(pad "DB2" thru_hole circle
			(at 14.249908 -6.800088)
			(size 0.7366 0.7366)
			(drill 0.369824)
			(layers "*.Cu" "*.Mask")
			(remove_unused_layers no)
			(net "8644_SDA_R_8")
			(clearance 0.1778)
			(thermal_gap 0.1778)
		)
		(pad "DB3" thru_hole circle
			(at 14.99997 -7.500112)
			(size 0.7366 0.7366)
			(drill 0.369824)
			(layers "*.Cu" "*.Mask")
			(remove_unused_layers no)
			(net "GND")
			(clearance 0.1778)
			(thermal_gap 0.1778)
		)
		(pad "DB4" thru_hole circle
			(at 15.750032 -8.199882)
			(size 0.7366 0.7366)
			(drill 0.369824)
			(layers "*.Cu" "*.Mask")
			(remove_unused_layers no)
			(net "PCIE_RX_P13")
			(clearance 0.1778)
			(thermal_gap 0.1778)
		)
		(pad "DB5" thru_hole circle
			(at 16.500094 -6.800088)
			(size 0.7366 0.7366)
			(drill 0.369824)
			(layers "*.Cu" "*.Mask")
			(remove_unused_layers no)
			(net "PCIE_RX_N13")
			(clearance 0.1778)
			(thermal_gap 0.1778)
		)
		(pad "DB6" thru_hole circle
			(at 17.249902 -7.500112)
			(size 0.7366 0.7366)
			(drill 0.369824)
			(layers "*.Cu" "*.Mask")
			(remove_unused_layers no)
			(net "GND")
			(clearance 0.1778)
			(thermal_gap 0.1778)
		)
		(pad "DB7" thru_hole circle
			(at 17.999964 -8.199882)
			(size 0.7366 0.7366)
			(drill 0.369824)
			(layers "*.Cu" "*.Mask")
			(remove_unused_layers no)
			(net "PCIE_RX_P14")
			(clearance 0.1778)
			(thermal_gap 0.1778)
		)
		(pad "DB8" thru_hole circle
			(at 18.750026 -6.800088)
			(size 0.7366 0.7366)
			(drill 0.369824)
			(layers "*.Cu" "*.Mask")
			(remove_unused_layers no)
			(net "PCIE_RX_N14")
			(clearance 0.1778)
			(thermal_gap 0.1778)
		)
		(pad "DB9" thru_hole circle
			(at 19.500088 -7.500112)
			(size 0.7366 0.7366)
			(drill 0.369824)
			(layers "*.Cu" "*.Mask")
			(remove_unused_layers no)
			(net "GND")
			(clearance 0.1778)
			(thermal_gap 0.1778)
		)
		(pad "DC1" thru_hole circle
			(at 13.5001 -11.999976)
			(size 0.7366 0.7366)
			(drill 0.369824)
			(layers "*.Cu" "*.Mask")
			(remove_unused_layers no)
			(net "BMC_I2C14_MINI8_SCL")
			(clearance 0.1778)
			(thermal_gap 0.1778)
		)
		(pad "DC2" thru_hole circle
			(at 14.249908 -10.599928)
			(size 0.7366 0.7366)
			(drill 0.369824)
			(layers "*.Cu" "*.Mask")
			(remove_unused_layers no)
			(net "8644_CBL_PRSNT_R_8")
			(clearance 0.1778)
			(thermal_gap 0.1778)
		)
		(pad "DC3" thru_hole circle
			(at 14.99997 -11.299952)
			(size 0.7366 0.7366)
			(drill 0.369824)
			(layers "*.Cu" "*.Mask")
			(remove_unused_layers no)
			(net "GND")
			(clearance 0.1778)
			(thermal_gap 0.1778)
		)
		(pad "DC4" thru_hole circle
			(at 15.750032 -11.999976)
			(size 0.7366 0.7366)
			(drill 0.369824)
			(layers "*.Cu" "*.Mask")
			(remove_unused_layers no)
			(net "PCIE_TX_P12")
			(clearance 0.1778)
			(thermal_gap 0.1778)
		)
		(pad "DC5" thru_hole circle
			(at 16.500094 -10.599928)
			(size 0.7366 0.7366)
			(drill 0.369824)
			(layers "*.Cu" "*.Mask")
			(remove_unused_layers no)
			(net "PCIE_TX_N12")
			(clearance 0.1778)
			(thermal_gap 0.1778)
		)
		(pad "DC6" thru_hole circle
			(at 17.249902 -11.299952)
			(size 0.7366 0.7366)
			(drill 0.369824)
			(layers "*.Cu" "*.Mask")
			(remove_unused_layers no)
			(net "GND")
			(clearance 0.1778)
			(thermal_gap 0.1778)
		)
		(pad "DC7" thru_hole circle
			(at 17.999964 -11.999976)
			(size 0.7366 0.7366)
			(drill 0.369824)
			(layers "*.Cu" "*.Mask")
			(remove_unused_layers no)
			(net "PCIE_TX_P15")
			(clearance 0.1778)
			(thermal_gap 0.1778)
		)
		(pad "DC8" thru_hole circle
			(at 18.750026 -10.599928)
			(size 0.7366 0.7366)
			(drill 0.369824)
			(layers "*.Cu" "*.Mask")
			(remove_unused_layers no)
			(net "PCIE_TX_N15")
			(clearance 0.1778)
			(thermal_gap 0.1778)
		)
		(pad "DC9" thru_hole circle
			(at 19.500088 -11.299952)
			(size 0.7366 0.7366)
			(drill 0.369824)
			(layers "*.Cu" "*.Mask")
			(remove_unused_layers no)
			(net "GND")
			(clearance 0.1778)
			(thermal_gap 0.1778)
		)
		(pad "DD1" thru_hole circle
			(at 13.5001 -15.80007)
			(size 0.7366 0.7366)
			(drill 0.369824)
			(layers "*.Cu" "*.Mask")
			(remove_unused_layers no)
			(net "8644_USB_DN8")
			(clearance 0.1778)
			(thermal_gap 0.1778)
		)
		(pad "DD2" thru_hole circle
			(at 14.249908 -14.400022)
			(size 0.7366 0.7366)
			(drill 0.369824)
			(layers "*.Cu" "*.Mask")
			(remove_unused_layers no)
			(net "8644_USB_DP8")
			(clearance 0.1778)
			(thermal_gap 0.1778)
		)
		(pad "DD3" thru_hole circle
			(at 14.99997 -15.100046)
			(size 0.7366 0.7366)
			(drill 0.369824)
			(layers "*.Cu" "*.Mask")
			(remove_unused_layers no)
			(net "GND")
			(clearance 0.1778)
			(thermal_gap 0.1778)
		)
		(pad "DD4" thru_hole circle
			(at 15.750032 -15.80007)
			(size 0.7366 0.7366)
			(drill 0.369824)
			(layers "*.Cu" "*.Mask")
			(remove_unused_layers no)
			(net "PCIE_TX_P13")
			(clearance 0.1778)
			(thermal_gap 0.1778)
		)
		(pad "DD5" thru_hole circle
			(at 16.500094 -14.400022)
			(size 0.7366 0.7366)
			(drill 0.369824)
			(layers "*.Cu" "*.Mask")
			(remove_unused_layers no)
			(net "PCIE_TX_N13")
			(clearance 0.1778)
			(thermal_gap 0.1778)
		)
		(pad "DD6" thru_hole circle
			(at 17.249902 -15.100046)
			(size 0.7366 0.7366)
			(drill 0.369824)
			(layers "*.Cu" "*.Mask")
			(remove_unused_layers no)
			(net "GND")
			(clearance 0.1778)
			(thermal_gap 0.1778)
		)
		(pad "DD7" thru_hole circle
			(at 17.999964 -15.80007)
			(size 0.7366 0.7366)
			(drill 0.369824)
			(layers "*.Cu" "*.Mask")
			(remove_unused_layers no)
			(net "PCIE_TX_P14")
			(clearance 0.1778)
			(thermal_gap 0.1778)
		)
		(pad "DD8" thru_hole circle
			(at 18.750026 -14.400022)
			(size 0.7366 0.7366)
			(drill 0.369824)
			(layers "*.Cu" "*.Mask")
			(remove_unused_layers no)
			(net "PCIE_TX_N14")
			(clearance 0.1778)
			(thermal_gap 0.1778)
		)
		(pad "DD9" thru_hole circle
			(at 19.500088 -15.100046)
			(size 0.7366 0.7366)
			(drill 0.369824)
			(layers "*.Cu" "*.Mask")
			(remove_unused_layers no)
			(net "GND")
			(clearance 0.1778)
			(thermal_gap 0.1778)
		)
		(pad "PTH1" thru_hole circle
			(at -21.999956 -3.700018)
			(size 0.9144 0.9144)
			(drill 0.569976)
			(layers "*.Cu" "*.Mask")
			(remove_unused_layers no)
			(net "GND")
			(clearance 0.1905)
			(thermal_gap 0.1905)
		)
		(pad "PTH2" thru_hole circle
			(at -17.999964 -17.509998)
			(size 0.9144 0.9144)
			(drill 0.569976)
			(layers "*.Cu" "*.Mask")
			(remove_unused_layers no)
			(net "GND")
			(clearance 0.1905)
			(thermal_gap 0.1905)
		)
		(pad "PTH3" thru_hole circle
			(at -13.5001 -17.509998)
			(size 0.9144 0.9144)
			(drill 0.569976)
			(layers "*.Cu" "*.Mask")
			(remove_unused_layers no)
			(net "GND")
			(clearance 0.1905)
			(thermal_gap 0.1905)
		)
		(pad "PTH4" thru_hole circle
			(at -6.999986 -17.509998)
			(size 0.9144 0.9144)
			(drill 0.569976)
			(layers "*.Cu" "*.Mask")
			(remove_unused_layers no)
			(net "GND")
			(clearance 0.1905)
			(thermal_gap 0.1905)
		)
		(pad "PTH5" thru_hole circle
			(at -2.500122 -17.509998)
			(size 0.9144 0.9144)
			(drill 0.569976)
			(layers "*.Cu" "*.Mask")
			(remove_unused_layers no)
			(net "GND")
			(clearance 0.1905)
			(thermal_gap 0.1905)
		)
		(pad "PTH6" thru_hole circle
			(at 3.999992 -17.509998)
			(size 0.9144 0.9144)
			(drill 0.569976)
			(layers "*.Cu" "*.Mask")
			(remove_unused_layers no)
			(net "GND")
			(clearance 0.1905)
			(thermal_gap 0.1905)
		)
		(pad "PTH7" thru_hole circle
			(at 8.50011 -17.509998)
			(size 0.9144 0.9144)
			(drill 0.569976)
			(layers "*.Cu" "*.Mask")
			(remove_unused_layers no)
			(net "GND")
			(clearance 0.1905)
			(thermal_gap 0.1905)
		)
		(pad "PTH8" thru_hole circle
			(at 14.99997 -17.509998)
			(size 0.9144 0.9144)
			(drill 0.569976)
			(layers "*.Cu" "*.Mask")
			(remove_unused_layers no)
			(net "GND")
			(clearance 0.1905)
			(thermal_gap 0.1905)
		)
		(pad "PTH9" thru_hole circle
			(at 19.500088 -17.509998)
			(size 0.9144 0.9144)
			(drill 0.569976)
			(layers "*.Cu" "*.Mask")
			(remove_unused_layers no)
			(net "GND")
			(clearance 0.1905)
			(thermal_gap 0.1905)
		)
	)
)
